FILE_TYPE = CONNECTIVITY;
{Allegro Design Entry HDL 17.2-2016 S081 (4005846) 1/11/2022}
"PAGE_NUMBER" = 228;
0"NC";
1"P3V3_AUX\g";
2"SMB_SML1_PMBUS_3V3AUX_PCH_SCL";
3"SMB_SML1_PMBUS_3V3AUX_PCH_SDA";
4"SMB_VR_3V3AUX_SDA_R3";
5"SMB_2_PLD_3V3AUX_SCL_R1";
6"SMB_VR_3V3AUX_SCL_R";
7"SMB_VR_3V3AUX_SCL";
8"SMB_1_PLD_3V3AUX_SCL_R1";
9"SMB_1_PLD_3V3AUX_SDA_R1";
10"SMB_VR_3V3AUX_SCL_R3";
11"SMB_1_PLD_3V3AUX_SDA";
12"SMB_1_PLD_3V3AUX_SCL";
13"SMB_VR_3V3AUX_SDA_R";
14"SMB_SML1_PMBUS_HSC_SDA";
15"SMB_SML1_PMBUS_HSC_SCL";
16"SMB_SML1_PMBUS_HSC_SDA_R3";
17"SMB_SML1_PMBUS_HSC_SCL_R3";
18"SMB_SML0_ME_SCL";
19"SMB_SML0_3V3AUX_PCH_SCL";
20"SMB_HOST_CLK_GEN2_3V3AUX_SDA";
21"SMB_HOST_CLK_BUF_3V3AUX_SDA";
22"SMB_HOST_3V3AUX_SDA_R5";
23"SMB_HOST_3V3AUX_SCL_R5";
24"SMB_HOST_3V3AUX_SDA_R";
25"SMB_HOST_3V3AUX_SCL_R";
26"SMB_HOST_3V3AUX_SCL";
27"SMB_HOST_3V3AUX_SDA_R4";
28"SMB_HOST_3V3AUX_SCL";
29"SMB_HOST_3V3AUX_SDA";
30"SMB_HOST_3V3AUX_SCL_R4";
31"SMB_HOST_3V3AUX_SDA";
32"SMB_HOST_3V3AUX_SDA_R";
33"SMB_HOST_CLK_3V3AUX_SCL";
34"SMB_HOST_CLK_3V3AUX_SDA";
35"SMB_HOST_3V3AUX_SCL_R";
36"SMB_SML0_3V3AUX_PCH_SDA";
37"SMB_SML0_ME_SDA";
38"SMB_HOST_CLK_3V3AUX_SCL";
39"SMB_HOST_CLK_3V3AUX_SDA";
40"SMB_HOST_CLK_GEN2_3V3AUX_SCL";
41"SMB_SML0_3V3AUX_SCL";
42"SMB_SML0_3V3AUX_SDA";
43"SMB_SML1_PMBUS_3V3AUX_PCH_SDA";
44"SMB_VR_3V3AUX_SDA_R";
45"SMB_PMBUS_SML1_ME_SDA";
46"SMB_SML1_PMBUS_3V3AUX_PCH_SCL";
47"SMB_VR_3V3AUX_SDA_R2";
48"SMB_VR_3V3AUX_SCL_R2";
49"SMB_2_PLD_3V3AUX_SDA_R1";
50"SMB_VR_3V3AUX_SDA";
51"SMB_PMBUS_SML1_ME_SCL";
52"I3C_BMC_SWB_SCL"CDS_PHYS_NET_NAME"SMB_SENSOR_3V3AUX_SCL";
53"I3C_BMC_SWB_SDA"CDS_PHYS_NET_NAME"SMB_SENSOR_3V3AUX_SDA";
54"SMB_VR_3V3AUX_SDA_R1";
55"SMB_VR_3V3AUX_SCL_R1";
56"SMB_1_BMC_GPU_SDA"CDS_PHYS_NET_NAME"SMB_SENSOR_3V3AUX_SDA";
57"SMB_1_BMC_GPU_SCL"CDS_PHYS_NET_NAME"SMB_SENSOR_3V3AUX_SCL";
58"SMB_HOST_CLK_BUF_3V3AUX_SCL";
59"SMB_HOST_3V3AUX_SDA_R4";
60"SMB_HOST_3V3AUX_SCL_R4";
61"SMB_HOST_BMC_3V3AUX_SCL";
62"SMB_HOST_BMC_3V3AUX_SDA";
63"SMB_SML1_PMBUS_HSC_SDA_R3";
64"SMB_SML1_PMBUS_HSC_SCL_R3";
65"SMB_VR_3V3AUX_SCL_R";
66"I3C_SPD_DDRABCD_CPU0_BMC_SCL";
67"I3C_SPD_DDRABCD_CPU0_BMC_SDA";
68"I3C_SPD_DDREFGH_CPU0_BMC_SCL";
69"I3C_SPD_DDREFGH_CPU0_BMC_SDA";
70"I3C_SPD_DDRABCD_CPU1_BMC_SCL";
71"I3C_SPD_DDRABCD_CPU1_BMC_SDA";
72"I3C_SPD_DDREFGH_CPU1_BMC_SCL";
73"I3C_SPD_DDREFGH_CPU1_BMC_SDA";
74"I3C_SPD_DDRABCD_CPU0_BMC_R_SCL";
75"I3C_SPD_DDRABCD_CPU0_BMC_R_SDA";
76"I3C_SPD_DDREFGH_CPU0_BMC_R_SCL";
77"I3C_SPD_DDREFGH_CPU0_BMC_R_SDA";
78"I3C_SPD_DDRABCD_CPU1_BMC_R_SCL";
79"I3C_SPD_DDRABCD_CPU1_BMC_R_SDA";
80"I3C_SPD_DDREFGH_CPU1_BMC_R_SDA";
81"I3C_SPD_DDREFGH_CPU1_BMC_R_SCL";
82"SMB_OCP_V3_2_3V3AUX_SDA";
83"SMB_OCP_V3_2_3V3AUX_SCL";
84"SMB_S3M_CPU_3V3AUX_SCL"CDS_PHYS_NET_NAME"SMB_SENSOR_3V3AUX_SCL";
85"SMB_S3M_CPU_3V3AUX_SDA"CDS_PHYS_NET_NAME"SMB_SENSOR_3V3AUX_SDA";
86"SMB_SML1_PMBUS_3V3AUX_PCH_SCL";
87"SMB_OCP_SFF_3V3AUX_SDA";
88"SMB_OCP_SFF_3V3AUX_SCL";
89"SMB_HOST_3V3AUX_SCL";
90"SMB_2_BMC_GPU_SCL"CDS_PHYS_NET_NAME"SMB_SENSOR_3V3AUX_SCL";
91"SMB_2_BMC_GPU_SDA"CDS_PHYS_NET_NAME"SMB_SENSOR_3V3AUX_SDA";
92"SMB_FAN_3V3AUX_SDA"CDS_PHYS_NET_NAME"SMB_FAN_3V3AUX_SDA";
93"SMB_FAN_3V3AUX_SCL"CDS_PHYS_NET_NAME"SMB_FAN_3V3AUX_SCL";
94"SMB_HOST_3V3AUX_SDA";
95"SMB_SML0_3V3AUX_SDA";
96"SMB_SML1_PMBUS_3V3AUX_PCH_SDA";
97"SMB_SML0_3V3AUX_SCL";
%"UNIVERSAL_POWER"
"1","(5550,6400)","0","logical_power","I1";
;
HDL_POWER"P3V3_AUX"
CDS_LIB"logical_power";
"A"1;
%"Q_RES"
"1","(5000,4925)","0","pure_quanta","I172";
;
PART_NUMBER"CS22202JB07"
VALUE"2.2K"
TOLERANCE"5%"
MATERIAL"EMPTY"
$LOCATION"R601"
CDS_LIB"pure_quanta"
PACK_TYPE"0402LF"
WATTAGE"1/16W"
$LOCATION"R601"
CDS_LOCATION"R601"
$SEC"1"
CDS_SEC"1";
"B"
$PN"2"1;
"A"
$PN"1"92;
%"Q_RES"
"1","(5000,4975)","0","pure_quanta","I173";
;
PART_NUMBER"CS22202JB07"
MATERIAL"EMPTY"
TOLERANCE"5%"
WATTAGE"1/16W"
PACK_TYPE"0402LF"
VALUE"2.2K"
$LOCATION"R592"
CDS_LIB"pure_quanta"
$LOCATION"R592"
CDS_LOCATION"R592"
$SEC"1"
CDS_SEC"1";
"B"
$PN"2"1;
"A"
$PN"1"93;
%"Q_RES"
"1","(5000,4325)","0","pure_quanta","I176";
;
PART_NUMBER"CS22202JB07"
VALUE"2.2K"
MATERIAL"EMPTY"
TOLERANCE"5%"
$LOCATION"R1460"
PACK_TYPE"0402LF"
WATTAGE"1/16W"
CDS_LIB"pure_quanta"
CDS_LOCATION"R1460"
$SEC"1"
CDS_SEC"1";
"B"
$PN"2"1;
"A"
$PN"1"53;
%"Q_RES"
"1","(5000,4375)","0","pure_quanta","I177";
;
PART_NUMBER"CS22202JB07"
MATERIAL"EMPTY"
TOLERANCE"5%"
VALUE"2.2K"
PACK_TYPE"0402LF"
WATTAGE"1/16W"
$LOCATION"R1336"
CDS_LIB"pure_quanta"
CDS_LOCATION"R1336"
$SEC"1"
CDS_SEC"1";
"B"
$PN"2"1;
"A"
$PN"1"52;
%"Q_RES"
"1","(5000,6075)","0","pure_quanta","I2";
;
PART_NUMBER"CS22002FB07"
MATERIAL"EMPTY"
PACK_TYPE"0402LF"
WATTAGE"1/16W"
VALUE"2K"
TOLERANCE"1%"
$LOCATION"R1319"
CDS_LIB"pure_quanta"
CDS_LOCATION"R1319"
$SEC"1"
CDS_SEC"1";
"B"
$PN"2"1;
"A"
$PN"1"89;
%"Q_RES"
"1","(5000,4075)","0","pure_quanta","I202";
;
PART_NUMBER"CS22202JB07"
PACK_TYPE"0402LF"
TOLERANCE"5%"
VALUE"2.2K"
MATERIAL"EMPTY"
WATTAGE"1/16W"
$LOCATION"R2212"
CDS_LIB"pure_quanta"
CDS_LOCATION"R2212"
$SEC"1"
CDS_SEC"1";
"B"
$PN"2"1;
"A"
$PN"1"84;
%"Q_RES"
"1","(5000,4025)","0","pure_quanta","I203";
;
PART_NUMBER"CS22202JB07"
TOLERANCE"5%"
VALUE"2.2K"
MATERIAL"EMPTY"
$LOCATION"R2213"
PACK_TYPE"0402LF"
WATTAGE"1/16W"
CDS_LIB"pure_quanta"
CDS_LOCATION"R2213"
$SEC"1"
CDS_SEC"1";
"B"
$PN"2"1;
"A"
$PN"1"85;
%"Q_RES"
"1","(-325,2450)","0","pure_quanta","I206";
;
PART_NUMBER"CS03322FB03"
WATTAGE"1/16W"
TOLERANCE"1%"
MATERIAL"CHIP"
VALUE"33.2"
PACK_TYPE"0402LF"
$LOCATION"R2449"
CDS_LIB"pure_quanta"
CDS_LOCATION"R2449"
$SEC"1"
CDS_SEC"1";
"B"
$PN"2"55;
"A"
$PN"1"7;
%"Q_RES"
"1","(-325,2400)","0","pure_quanta","I207";
;
PART_NUMBER"CS03322FB03"
TOLERANCE"1%"
MATERIAL"CHIP"
VALUE"33.2"
$LOCATION"R2450"
PACK_TYPE"0402LF"
WATTAGE"1/16W"
CDS_LIB"pure_quanta"
CDS_LOCATION"R2450"
$SEC"1"
CDS_SEC"1";
"B"
$PN"2"54;
"A"
$PN"1"50;
%"Q_RES"
"1","(-350,1800)","0","pure_quanta","I216";
;
PART_NUMBER"CS03322FB03"
VALUE"33.2"
TOLERANCE"1%"
MATERIAL"CHIP"
$LOCATION"R2456"
PACK_TYPE"0402LF"
WATTAGE"1/16W"
CDS_LIB"pure_quanta"
CDS_LOCATION"R2456"
$SEC"1"
CDS_SEC"1";
"B"
$PN"2"4;
"A"
$PN"1"13;
%"Q_RES"
"1","(-350,1850)","0","pure_quanta","I217";
;
PART_NUMBER"CS03322FB03"
VALUE"33.2"
TOLERANCE"1%"
PACK_TYPE"0402LF"
WATTAGE"1/16W"
MATERIAL"CHIP"
$LOCATION"R2455"
CDS_LIB"pure_quanta"
CDS_LOCATION"R2455"
$SEC"1"
CDS_SEC"1";
"B"
$PN"2"10;
"A"
$PN"1"6;
%"Q_RES"
"1","(-350,2075)","0","pure_quanta","I218";
;
PART_NUMBER"CS03322FB03"
TOLERANCE"1%"
MATERIAL"CHIP"
VALUE"33.2"
$LOCATION"R2454"
WATTAGE"1/16W"
PACK_TYPE"0402LF"
CDS_LIB"pure_quanta"
CDS_LOCATION"R2454"
$SEC"1"
CDS_SEC"1";
"B"
$PN"2"47;
"A"
$PN"1"13;
%"Q_RES"
"1","(-350,2125)","0","pure_quanta","I219";
;
PART_NUMBER"CS03322FB03"
WATTAGE"1/16W"
TOLERANCE"1%"
MATERIAL"CHIP"
PACK_TYPE"0402LF"
VALUE"33.2"
$LOCATION"R2453"
CDS_LIB"pure_quanta"
CDS_LOCATION"R2453"
$SEC"1"
CDS_SEC"1";
"B"
$PN"2"48;
"A"
$PN"1"6;
%"Q_RES"
"1","(-300,3925)","0","pure_quanta","I228";
;
PART_NUMBER"CS03322FB03"
WATTAGE"1/16W"
PACK_TYPE"0402LF"
MATERIAL"CHIP"
VALUE"33.2"
TOLERANCE"1%"
$LOCATION"R2995"
CDS_LIB"pure_quanta"
CDS_LOCATION"R2995"
$SEC"1"
CDS_SEC"1";
"B"
$PN"2"17;
"A"
$PN"1"46;
%"Q_RES"
"1","(-300,3875)","0","pure_quanta","I229";
;
PART_NUMBER"CS03322FB03"
TOLERANCE"1%"
VALUE"33.2"
MATERIAL"CHIP"
$LOCATION"R2996"
PACK_TYPE"0402LF"
WATTAGE"1/16W"
CDS_LIB"pure_quanta"
CDS_LOCATION"R2996"
$SEC"1"
CDS_SEC"1";
"B"
$PN"2"16;
"A"
$PN"1"43;
%"Q_RES"
"1","(5000,3650)","0","pure_quanta","I230";
;
PART_NUMBER"CS22202JB07"
TOLERANCE"5%"
MATERIAL"EMPTY"
VALUE"2.2K"
$LOCATION"R3004"
PACK_TYPE"0402LF"
WATTAGE"1/16W"
CDS_LIB"pure_quanta"
CDS_LOCATION"R3004"
$SEC"1"
CDS_SEC"1";
"B"
$PN"2"1;
"A"
$PN"1"91;
%"Q_RES"
"1","(5000,3700)","0","pure_quanta","I231";
;
PART_NUMBER"CS22202JB07"
WATTAGE"1/16W"
PACK_TYPE"0402LF"
TOLERANCE"5%"
MATERIAL"EMPTY"
VALUE"2.2K"
$LOCATION"R2999"
CDS_LIB"pure_quanta"
CDS_LOCATION"R2999"
$SEC"1"
CDS_SEC"1";
"B"
$PN"2"1;
"A"
$PN"1"90;
%"Q_RES"
"1","(-325,3000)","0","pure_quanta","I234";
;
PART_NUMBER"CS03322FB03"
MATERIAL"CHIP"
TOLERANCE"1%"
VALUE"33.2"
$LOCATION"R3061"
PACK_TYPE"0402LF"
WATTAGE"1/16W"
CDS_LIB"pure_quanta"
CDS_LOCATION"R3061"
$SEC"1"
CDS_SEC"1";
"B"
$PN"2"45;
"A"
$PN"1"3;
%"Q_RES"
"1","(-325,3050)","0","pure_quanta","I237";
;
PART_NUMBER"CS03322FB03"
MATERIAL"CHIP"
VALUE"33.2"
PACK_TYPE"0402LF"
WATTAGE"1/16W"
TOLERANCE"1%"
$LOCATION"R3060"
CDS_LIB"pure_quanta"
CDS_LOCATION"R3060"
$SEC"1"
CDS_SEC"1";
"B"
$PN"2"51;
"A"
$PN"1"2;
%"Q_RES"
"1","(-300,4275)","0","pure_quanta","I242";
;
PART_NUMBER"CS03322FB03"
WATTAGE"1/16W"
VALUE"33.2"
MATERIAL"CHIP"
TOLERANCE"1%"
PACK_TYPE"0402LF"
$LOCATION"R3058"
CDS_LIB"pure_quanta"
CDS_LOCATION"R3058"
$SEC"1"
CDS_SEC"1";
"B"
$PN"2"18;
"A"
$PN"1"41;
%"Q_RES"
"1","(-300,4225)","0","pure_quanta","I243";
;
PART_NUMBER"CS03322FB03"
TOLERANCE"1%"
VALUE"33.2"
MATERIAL"CHIP"
$LOCATION"R3059"
PACK_TYPE"0402LF"
WATTAGE"1/16W"
CDS_LIB"pure_quanta"
CDS_LOCATION"R3059"
$SEC"1"
CDS_SEC"1";
"B"
$PN"2"37;
"A"
$PN"1"42;
%"Q_RES"
"1","(5000,3250)","0","pure_quanta","I250";
;
PART_NUMBER"CS22202JB07"
VALUE"2.2K"
TOLERANCE"5%"
MATERIAL"EMPTY"
$LOCATION"R3227"
CDS_LIB"pure_quanta"
WATTAGE"1/16W"
PACK_TYPE"0402LF"
CDS_LOCATION"R3227"
$SEC"1"
CDS_SEC"1";
"B"
$PN"2"1;
"A"
$PN"1"56;
%"Q_RES"
"1","(5000,3300)","0","pure_quanta","I251";
;
PART_NUMBER"CS22202JB07"
VALUE"2.2K"
WATTAGE"1/16W"
TOLERANCE"5%"
MATERIAL"EMPTY"
PACK_TYPE"0402LF"
$LOCATION"R3226"
CDS_LIB"pure_quanta"
CDS_LOCATION"R3226"
$SEC"1"
CDS_SEC"1";
"B"
$PN"2"1;
"A"
$PN"1"57;
%"Q_RES"
"1","(5000,2975)","0","pure_quanta","I258";
;
PART_NUMBER"CS22202JB07"
TOLERANCE"5%"
MATERIAL"EMPTY"
VALUE"2.2K"
$LOCATION"R3241"
PACK_TYPE"0402LF"
WATTAGE"1/16W"
CDS_LIB"pure_quanta"
CDS_LOCATION"R3241"
$SEC"1"
CDS_SEC"1";
"B"
$PN"2"1;
"A"
$PN"1"87;
%"Q_RES"
"1","(5000,3025)","0","pure_quanta","I259";
;
PART_NUMBER"CS22202JB07"
PACK_TYPE"0402LF"
MATERIAL"EMPTY"
TOLERANCE"5%"
VALUE"2.2K"
WATTAGE"1/16W"
$LOCATION"R3240"
CDS_LIB"pure_quanta"
CDS_LOCATION"R3240"
$SEC"1"
CDS_SEC"1";
"B"
$PN"2"1;
"A"
$PN"1"88;
%"Q_RES"
"1","(5000,2725)","0","pure_quanta","I260";
;
PART_NUMBER"CS22202JB07"
PACK_TYPE"0402LF"
WATTAGE"1/16W"
TOLERANCE"5%"
VALUE"2.2K"
MATERIAL"EMPTY"
$LOCATION"R3242"
CDS_LIB"pure_quanta"
CDS_LOCATION"R3242"
$SEC"1"
CDS_SEC"1";
"B"
$PN"2"1;
"A"
$PN"1"83;
%"Q_RES"
"1","(5000,2675)","0","pure_quanta","I261";
;
PART_NUMBER"CS22202JB07"
MATERIAL"EMPTY"
TOLERANCE"5%"
VALUE"2.2K"
$LOCATION"R3243"
CDS_LIB"pure_quanta"
PACK_TYPE"0402LF"
WATTAGE"1/16W"
CDS_LOCATION"R3243"
$SEC"1"
CDS_SEC"1";
"B"
$PN"2"1;
"A"
$PN"1"82;
%"Q_RES"
"1","(-325,4800)","0","pure_quanta","I264";
;
PART_NUMBER"CS03322FB03"
MATERIAL"CHIP"
TOLERANCE"1%"
PACK_TYPE"0402LF"
WATTAGE"1/16W"
VALUE"33.2"
$LOCATION"R3341"
CDS_LIB"pure_quanta"
CDS_LOCATION"R3341"
$SEC"1"
CDS_SEC"1";
"B"
$PN"2"20;
"A"
$PN"1"34;
%"Q_RES"
"1","(-325,4850)","0","pure_quanta","I268";
;
PART_NUMBER"CS03322FB03"
TOLERANCE"1%"
MATERIAL"CHIP"
PACK_TYPE"0402LF"
WATTAGE"1/16W"
VALUE"33.2"
$LOCATION"R3340"
CDS_LIB"pure_quanta"
CDS_LOCATION"R3340"
$SEC"1"
CDS_SEC"1";
"B"
$PN"2"40;
"A"
$PN"1"33;
%"Q_RES"
"1","(-350,975)","0","pure_quanta","I271";
;
PART_NUMBER"CS03322FB03"
TOLERANCE"1%"
VALUE"33.2"
MATERIAL"CHIP"
$LOCATION"R4150"
PACK_TYPE"0402LF"
WATTAGE"1/16W"
CDS_LIB"pure_quanta"
CDS_LOCATION"R4150"
$SEC"1"
CDS_SEC"1";
"B"
$PN"2"9;
"A"
$PN"1"11;
%"Q_RES"
"1","(-350,1025)","0","pure_quanta","I272";
;
PART_NUMBER"CS03322FB03"
VALUE"33.2"
TOLERANCE"1%"
MATERIAL"CHIP"
PACK_TYPE"0402LF"
WATTAGE"1/16W"
$LOCATION"R4149"
CDS_LIB"pure_quanta"
CDS_LOCATION"R4149"
$SEC"1"
CDS_SEC"1";
"B"
$PN"2"8;
"A"
$PN"1"12;
%"Q_RES"
"1","(-350,700)","0","pure_quanta","I273";
;
PART_NUMBER"CS03322FB03"
TOLERANCE"1%"
VALUE"33.2"
MATERIAL"CHIP"
$LOCATION"R4152"
CDS_LIB"pure_quanta"
PACK_TYPE"0402LF"
WATTAGE"1/16W"
CDS_LOCATION"R4152"
$SEC"1"
CDS_SEC"1";
"B"
$PN"2"49;
"A"
$PN"1"11;
%"Q_RES"
"1","(-350,750)","0","pure_quanta","I274";
;
PART_NUMBER"CS03322FB03"
WATTAGE"1/16W"
PACK_TYPE"0402LF"
VALUE"33.2"
MATERIAL"CHIP"
TOLERANCE"1%"
$LOCATION"R4151"
CDS_LIB"pure_quanta"
CDS_LOCATION"R4151"
$SEC"1"
CDS_SEC"1";
"B"
$PN"2"5;
"A"
$PN"1"12;
%"Q_RES"
"1","(-350,6675)","0","pure_quanta","I284";
;
PART_NUMBER"CS00002JB13"
VALUE"0"
MATERIAL"CHIP"
TOLERANCE"5%"
$LOCATION"R4511"
WATTAGE"1/16W"
PACK_TYPE"0402LF"
CDS_LIB"pure_quanta"
CDS_LOCATION"R4511"
$SEC"1"
CDS_SEC"1";
"B"
$PN"2"59;
"A"
$PN"1"31;
%"Q_RES"
"1","(-350,6725)","0","pure_quanta","I285";
;
PART_NUMBER"CS03322FB03"
VALUE"33.2"
TOLERANCE"1%"
WATTAGE"1/16W"
MATERIAL"CHIP"
PACK_TYPE"0402LF"
$LOCATION"R4510"
CDS_LIB"pure_quanta"
CDS_LOCATION"R4510"
$SEC"1"
CDS_SEC"1";
"B"
$PN"2"60;
"A"
$PN"1"26;
%"Q_RES"
"1","(-300,3525)","0","pure_quanta","I293";
;
PART_NUMBER"CS03322FB03"
TOLERANCE"1%"
VALUE"33.2"
WATTAGE"1/16W"
PACK_TYPE"0402LF"
MATERIAL"CHIP"
LOCATION"R4530"
CDS_LIB"pure_quanta"
$SEC"1"
CDS_SEC"1";
"B"
$PN"2"15;
"A"
$PN"1"64;
%"Q_RES"
"1","(-300,3475)","0","pure_quanta","I296";
;
PART_NUMBER"CS00002JB13"
TOLERANCE"5%"
MATERIAL"CHIP"
VALUE"0"
LOCATION"R4531"
CDS_LIB"pure_quanta"
WATTAGE"1/16W"
PACK_TYPE"0402LF"
$SEC"1"
CDS_SEC"1";
"B"
$PN"2"14;
"A"
$PN"1"63;
%"Q_RES"
"1","(5000,6025)","0","pure_quanta","I3";
;
PART_NUMBER"CS22002FB07"
MATERIAL"EMPTY"
VALUE"2K"
TOLERANCE"1%"
$LOCATION"R3062"
CDS_LIB"pure_quanta"
WATTAGE"1/16W"
PACK_TYPE"0402LF"
CDS_LOCATION"R3062"
$SEC"1"
CDS_SEC"1";
"B"
$PN"2"1;
"A"
$PN"1"94;
%"Q_RES"
"1","(-350,6400)","0","pure_quanta","I303";
;
PART_NUMBER"CS03322FB03"
MATERIAL"CHIP"
WATTAGE"1/16W"
TOLERANCE"1%"
PACK_TYPE"0402LF"
VALUE"33.2"
$LOCATION"R577"
CDS_LIB"pure_quanta"
CDS_LOCATION"R577"
$SEC"1"
CDS_SEC"1";
"B"
$PN"2"25;
"A"
$PN"1"30;
%"Q_RES"
"1","(-350,6350)","0","pure_quanta","I304";
;
PART_NUMBER"CS03322FB03"
MATERIAL"CHIP"
TOLERANCE"1%"
VALUE"33.2"
$LOCATION"R578"
PACK_TYPE"0402LF"
CDS_LIB"pure_quanta"
WATTAGE"1/16W"
CDS_LOCATION"R578"
$SEC"1"
CDS_SEC"1";
"B"
$PN"2"24;
"A"
$PN"1"27;
%"Q_RES"
"1","(-1225,6050)","0","pure_quanta","I305";
;
PART_NUMBER"CS03322FB03"
WATTAGE"1/16W"
VALUE"33.2"
TOLERANCE"1%"
MATERIAL"CHIP"
PACK_TYPE"0402LF"
$LOCATION"R4512"
CDS_LIB"pure_quanta"
CDS_LOCATION"R4512"
$SEC"1"
CDS_SEC"1";
"B"
$PN"2"23;
"A"
$PN"1"28;
%"Q_RES"
"1","(-1225,6000)","0","pure_quanta","I306";
;
PART_NUMBER"CS00002JB13"
VALUE"0"
TOLERANCE"5%"
MATERIAL"CHIP"
$LOCATION"R4513"
CDS_LIB"pure_quanta"
PACK_TYPE"0402LF"
WATTAGE"1/16W"
CDS_LOCATION"R4513"
$SEC"1"
CDS_SEC"1";
"B"
$PN"2"22;
"A"
$PN"1"29;
%"Q_RES"
"1","(3875,2050)","0","pure_quanta","I311";
;
PART_NUMBER"CS00002JB13"
TOLERANCE"5%"
VALUE"0"
MATERIAL"CHIP"
LOCATION"R593"
WATTAGE"1/16W"
PACK_TYPE"0402LF"
CDS_LIB"pure_quanta"
$SEC"1"
CDS_SEC"1";
"B"
$PN"2"66;
"A"
$PN"1"74;
%"Q_RES"
"1","(3875,2000)","0","pure_quanta","I312";
;
PART_NUMBER"CS00002JB13"
TOLERANCE"5%"
VALUE"0"
MATERIAL"CHIP"
LOCATION"R594"
WATTAGE"1/16W"
PACK_TYPE"0402LF"
CDS_LIB"pure_quanta"
$SEC"1"
CDS_SEC"1";
"B"
$PN"2"67;
"A"
$PN"1"75;
%"Q_RES"
"1","(3875,1700)","0","pure_quanta","I313";
;
PART_NUMBER"CS00002JB13"
MATERIAL"CHIP"
VALUE"0"
TOLERANCE"5%"
LOCATION"R596"
CDS_LIB"pure_quanta"
PACK_TYPE"0402LF"
WATTAGE"1/16W"
$SEC"1"
CDS_SEC"1";
"B"
$PN"2"69;
"A"
$PN"1"77;
%"Q_RES"
"1","(3875,1750)","0","pure_quanta","I314";
;
PART_NUMBER"CS00002JB13"
MATERIAL"CHIP"
VALUE"0"
TOLERANCE"5%"
LOCATION"R595"
CDS_LIB"pure_quanta"
PACK_TYPE"0402LF"
WATTAGE"1/16W"
$SEC"1"
CDS_SEC"1";
"B"
$PN"2"68;
"A"
$PN"1"76;
%"Q_RES"
"1","(3875,1375)","0","pure_quanta","I315";
;
PART_NUMBER"CS00002JB13"
TOLERANCE"5%"
MATERIAL"CHIP"
VALUE"0"
LOCATION"R598"
CDS_LIB"pure_quanta"
PACK_TYPE"0402LF"
WATTAGE"1/16W"
$SEC"1"
CDS_SEC"1";
"B"
$PN"2"71;
"A"
$PN"1"79;
%"Q_RES"
"1","(3875,1425)","0","pure_quanta","I316";
;
PART_NUMBER"CS00002JB13"
MATERIAL"CHIP"
VALUE"0"
TOLERANCE"5%"
LOCATION"R597"
CDS_LIB"pure_quanta"
PACK_TYPE"0402LF"
WATTAGE"1/16W"
$SEC"1"
CDS_SEC"1";
"B"
$PN"2"70;
"A"
$PN"1"78;
%"Q_RES"
"1","(3875,1125)","0","pure_quanta","I317";
;
PART_NUMBER"CS00002JB13"
TOLERANCE"5%"
VALUE"0"
MATERIAL"CHIP"
LOCATION"R599"
WATTAGE"1/16W"
PACK_TYPE"0402LF"
CDS_LIB"pure_quanta"
$SEC"1"
CDS_SEC"1";
"B"
$PN"2"72;
"A"
$PN"1"81;
%"Q_RES"
"1","(3875,1075)","0","pure_quanta","I318";
;
PART_NUMBER"CS00002JB13"
TOLERANCE"5%"
VALUE"0"
MATERIAL"CHIP"
LOCATION"R600"
WATTAGE"1/16W"
PACK_TYPE"0402LF"
CDS_LIB"pure_quanta"
$SEC"1"
CDS_SEC"1";
"B"
$PN"2"73;
"A"
$PN"1"80;
%"Q_RES"
"1","(-200,5800)","0","pure_quanta","I38";
;
PART_NUMBER"CS03322FB03"
WATTAGE"1/16W"
TOLERANCE"1%"
MATERIAL"CHIP"
VALUE"33.2"
PACK_TYPE"0402LF"
$LOCATION"R579"
CDS_LIB"pure_quanta"
CDS_LOCATION"R579"
$SEC"1"
CDS_SEC"1";
"B"
$PN"2"61;
"A"
$PN"1"23;
%"Q_RES"
"1","(-200,5750)","0","pure_quanta","I39";
;
PART_NUMBER"CS03322FB03"
MATERIAL"CHIP"
VALUE"33.2"
TOLERANCE"1%"
$LOCATION"R580"
PACK_TYPE"0402LF"
WATTAGE"1/16W"
CDS_LIB"pure_quanta"
CDS_LOCATION"R580"
$SEC"1"
CDS_SEC"1";
"B"
$PN"2"62;
"A"
$PN"1"22;
%"Q_RES"
"1","(5000,5825)","0","pure_quanta","I4";
;
PART_NUMBER"CS22002FB07"
MATERIAL"EMPTY"
VALUE"2K"
PACK_TYPE"0402LF"
WATTAGE"1/16W"
TOLERANCE"1%"
$LOCATION"R1384"
CDS_LIB"pure_quanta"
CDS_LOCATION"R1384"
$SEC"1"
CDS_SEC"1";
"B"
$PN"2"1;
"A"
$PN"1"97;
%"Q_RES"
"1","(-350,5500)","0","pure_quanta","I40";
;
PART_NUMBER"CS00002JB13"
TOLERANCE"5%"
MATERIAL"CHIP"
VALUE"0"
$LOCATION"R1525"
CDS_LIB"pure_quanta"
WATTAGE"1/16W"
PACK_TYPE"0402LF"
CDS_LOCATION"R1525"
$SEC"1"
CDS_SEC"1";
"B"
$PN"2"38;
"A"
$PN"1"35;
%"Q_RES"
"1","(-350,5450)","0","pure_quanta","I41";
;
PART_NUMBER"CS03322FB03"
MATERIAL"CHIP"
TOLERANCE"1%"
VALUE"33.2"
WATTAGE"1/16W"
PACK_TYPE"0402LF"
$LOCATION"R1526"
CDS_LIB"pure_quanta"
CDS_LOCATION"R1526"
$SEC"1"
CDS_SEC"1";
"B"
$PN"2"39;
"A"
$PN"1"32;
%"Q_RES"
"1","(-350,5125)","0","pure_quanta","I42";
;
PART_NUMBER"CS03322FB03"
MATERIAL"CHIP"
TOLERANCE"1%"
VALUE"33.2"
PACK_TYPE"0402LF"
WATTAGE"1/16W"
$LOCATION"R108"
CDS_LIB"pure_quanta"
CDS_LOCATION"R108"
$SEC"1"
CDS_SEC"1";
"B"
$PN"2"21;
"A"
$PN"1"32;
%"Q_RES"
"1","(-350,5175)","0","pure_quanta","I43";
;
PART_NUMBER"CS03322FB03"
VALUE"33.2"
MATERIAL"CHIP"
TOLERANCE"1%"
$LOCATION"R107"
CDS_LIB"pure_quanta"
WATTAGE"1/16W"
PACK_TYPE"0402LF"
CDS_LOCATION"R107"
$SEC"1"
CDS_SEC"1";
"B"
$PN"2"58;
"A"
$PN"1"35;
%"Q_RES"
"1","(-325,4550)","0","pure_quanta","I44";
;
PART_NUMBER"CS03322FB03"
VALUE"33.2"
TOLERANCE"1%"
WATTAGE"1/16W"
PACK_TYPE"0402LF"
MATERIAL"CHIP"
$LOCATION"R581"
CDS_LIB"pure_quanta"
CDS_LOCATION"R581"
$SEC"1"
CDS_SEC"1";
"B"
$PN"2"19;
"A"
$PN"1"41;
%"Q_RES"
"1","(-325,4500)","0","pure_quanta","I45";
;
PART_NUMBER"CS03322FB03"
TOLERANCE"1%"
VALUE"33.2"
MATERIAL"CHIP"
$LOCATION"R582"
PACK_TYPE"0402LF"
WATTAGE"1/16W"
CDS_LIB"pure_quanta"
CDS_LOCATION"R582"
$SEC"1"
CDS_SEC"1";
"B"
$PN"2"36;
"A"
$PN"1"42;
%"Q_RES"
"1","(5000,5775)","0","pure_quanta","I5";
;
PART_NUMBER"CS22002FB07"
MATERIAL"EMPTY"
TOLERANCE"1%"
VALUE"2K"
$LOCATION"R1385"
PACK_TYPE"0402LF"
WATTAGE"1/16W"
CDS_LIB"pure_quanta"
CDS_LOCATION"R1385"
$SEC"1"
CDS_SEC"1";
"B"
$PN"2"1;
"A"
$PN"1"95;
%"Q_RES"
"1","(5000,5575)","0","pure_quanta","I6";
;
PART_NUMBER"CS22002FB07"
TOLERANCE"1%"
MATERIAL"EMPTY"
PACK_TYPE"0402LF"
WATTAGE"1/16W"
VALUE"2K"
$LOCATION"R1386"
CDS_LIB"pure_quanta"
CDS_LOCATION"R1386"
$SEC"1"
CDS_SEC"1";
"B"
$PN"2"1;
"A"
$PN"1"86;
%"Q_RES"
"1","(5000,5525)","0","pure_quanta","I7";
;
PART_NUMBER"CS22002FB07"
VALUE"2K"
MATERIAL"EMPTY"
TOLERANCE"1%"
$LOCATION"R1387"
CDS_LIB"pure_quanta"
WATTAGE"1/16W"
PACK_TYPE"0402LF"
CDS_LOCATION"R1387"
$SEC"1"
CDS_SEC"1";
"B"
$PN"2"1;
"A"
$PN"1"96;
%"Q_RES"
"1","(-325,2725)","0","pure_quanta","I89";
;
PART_NUMBER"CS03322FB03"
WATTAGE"1/16W"
TOLERANCE"1%"
VALUE"33.2"
MATERIAL"CHIP"
PACK_TYPE"0402LF"
$LOCATION"R1661"
CDS_LIB"pure_quanta"
CDS_LOCATION"R1661"
$SEC"1"
CDS_SEC"1";
"B"
$PN"2"65;
"A"
$PN"1"7;
%"Q_RES"
"1","(-325,2675)","0","pure_quanta","I90";
;
PART_NUMBER"CS03322FB03"
MATERIAL"CHIP"
VALUE"33.2"
TOLERANCE"1%"
$LOCATION"R1662"
CDS_LIB"pure_quanta"
PACK_TYPE"0402LF"
WATTAGE"1/16W"
CDS_LOCATION"R1662"
$SEC"1"
CDS_SEC"1";
"B"
$PN"2"44;
"A"
$PN"1"50;
END.
